# T6G (Grand Teton) — schematic netlist excerpt (pin names and nets, part order shuffled) for the footprints in the layout excerpt that follows; sources: Cadence DE-HDL packaged netlist, KiCad conversion of 04192023_DAF0TMB3IC0_F0TG_MB_C_brd_V02_OCP.brd

R3234  Q_RES  33.2 1% CHIP  pkg 0402LF  page 139 : A = OCP_V3_2_AUX_PWR_EN ; B = OCP_V3_2_AUX_PWR_EN_R3
R3616  Q_RES  4.7K 1% CHIP  pkg 0402LF  page 236 : A = GND ; B = INA230_1_A1

(kicad_pcb
	(version 20260206)
	(generator "pcbnew")
	(generator_version "10.0")
	(general
		(thickness 1.6)
		(legacy_teardrops no)
	)
	(paper "A4")
	(title_block
		(title "04192023_DAF0TMB3IC0_F0TG_MB_C_brd_V02_OCP.brd")
		(comment 1 "Grand Teton / footprints 2549-2550 of 8354")
	)
	(layers
		(0 "F.Cu" signal "TOP")
		(4 "In1.Cu" signal "GND")
		(6 "In2.Cu" signal "IN1")
		(8 "In3.Cu" signal "GND1")
		(10 "In4.Cu" signal "IN2")
		(12 "In5.Cu" signal "GND2")
		(14 "In6.Cu" signal "IN3")
		(16 "In7.Cu" signal "GND3")
		(18 "In8.Cu" signal "VCC")
		(20 "In9.Cu" signal "VCC1")
		(22 "In10.Cu" signal "GND4")
		(24 "In11.Cu" signal "IN4")
		(26 "In12.Cu" signal "GND5")
		(28 "In13.Cu" signal "IN5")
		(30 "In14.Cu" signal "GND6")
		(32 "In15.Cu" signal "IN6")
		(34 "In16.Cu" signal "GND7")
		(2 "B.Cu" signal "BOTTOM")
		(9 "F.Adhes" user "F.Adhesive")
		(11 "B.Adhes" user "B.Adhesive")
		(13 "F.Paste" user "Package Geometry/Pastemask Top")
		(15 "B.Paste" user "Package Geometry/Pastemask Bottom")
		(5 "F.SilkS" user "Ref Des/Silkscreen Top")
		(7 "B.SilkS" user "Ref Des/Silkscreen Bottom")
		(1 "F.Mask" user "Board Geometry/Soldermask Top")
		(3 "B.Mask" user "Board Geometry/Soldermask Bottom")
		(17 "Dwgs.User" user "User.Drawings")
		(19 "Cmts.User" user "User.Comments")
		(21 "Eco1.User" user "User.Eco1")
		(23 "Eco2.User" user "User.Eco2")
		(25 "Edge.Cuts" user "Board Geometry/Outline")
		(27 "Margin" user)
		(31 "F.CrtYd" user "Package Geometry/Place Bound Top")
		(29 "B.CrtYd" user "Package Geometry/Place Bound Bottom")
		(35 "F.Fab" user "Ref Des/Assembly Top")
		(33 "B.Fab" user "Ref Des/Assembly Bottom")
	)
	(footprint ""
		(layer "F.Cu")
		(at 448.672458 -92.493592 180)
		(property "Reference" "R3616"
			(at 0 0 180)
			(layer "F.SilkS")
			(hide yes)
			(effects
				(font
					(size 1.27 1.27)
				)
			)
		)
		(property "Value" ""
			(at 0 0 180)
			(layer "F.Fab")
			(effects
				(font
					(size 1.27 1.27)
				)
			)
		)
		(duplicate_pad_numbers_are_jumpers no)
		(fp_line
			(start 0.7874 0.4064)
			(end -0.7874 0.4064)
			(stroke
				(width 0.1524)
				(type default)
			)
			(layer "F.SilkS")
		)
		(fp_line
			(start 0.7874 -0.4064)
			(end 0.7874 0.4064)
			(stroke
				(width 0.1524)
				(type default)
			)
			(layer "F.SilkS")
		)
		(fp_line
			(start -0.7874 0.4064)
			(end -0.7874 -0.4064)
			(stroke
				(width 0.1524)
				(type default)
			)
			(layer "F.SilkS")
		)
		(fp_line
			(start -0.7874 -0.4064)
			(end 0.7874 -0.4064)
			(stroke
				(width 0.1524)
				(type default)
			)
			(layer "F.SilkS")
		)
		(fp_line
			(start 0.67945 0.3048)
			(end 0.120396 0.3048)
			(stroke
				(width 0.1)
				(type default)
			)
			(layer "F.Fab")
		)
		(fp_line
			(start 0.67945 -0.3048)
			(end 0.67945 0.3048)
			(stroke
				(width 0.1)
				(type default)
			)
			(layer "F.Fab")
		)
		(fp_line
			(start 0.12065 -0.2794)
			(end 0.12065 -0.3048)
			(stroke
				(width 0.1)
				(type default)
			)
			(layer "F.Fab")
		)
		(fp_line
			(start 0.12065 -0.3048)
			(end 0.67945 -0.3048)
			(stroke
				(width 0.1)
				(type default)
			)
			(layer "F.Fab")
		)
		(fp_line
			(start 0.120396 0.3048)
			(end 0.120396 0.2794)
			(stroke
				(width 0.1)
				(type default)
			)
			(layer "F.Fab")
		)
		(fp_line
			(start 0.120396 0.2794)
			(end -0.12065 0.2794)
			(stroke
				(width 0.1)
				(type default)
			)
			(layer "F.Fab")
		)
		(fp_line
			(start -0.12065 0.3048)
			(end -0.67945 0.3048)
			(stroke
				(width 0.1)
				(type default)
			)
			(layer "F.Fab")
		)
		(fp_line
			(start -0.12065 0.2794)
			(end -0.12065 0.3048)
			(stroke
				(width 0.1)
				(type default)
			)
			(layer "F.Fab")
		)
		(fp_line
			(start -0.12065 -0.2794)
			(end 0.12065 -0.2794)
			(stroke
				(width 0.1)
				(type default)
			)
			(layer "F.Fab")
		)
		(fp_line
			(start -0.12065 -0.305054)
			(end -0.12065 -0.2794)
			(stroke
				(width 0.1)
				(type default)
			)
			(layer "F.Fab")
		)
		(fp_line
			(start -0.67945 0.3048)
			(end -0.67945 -0.305054)
			(stroke
				(width 0.1)
				(type default)
			)
			(layer "F.Fab")
		)
		(fp_line
			(start -0.67945 -0.305054)
			(end -0.12065 -0.305054)
			(stroke
				(width 0.1)
				(type default)
			)
			(layer "F.Fab")
		)
		(pad "1" smd circle
			(at -0.40005 0 180)
			(size 0 0)
			(layers "F.Cu" "F.Mask" "F.Paste")
			(net "GND")
		)
		(pad "2" smd circle
			(at 0.40005 0 180)
			(size 0 0)
			(layers "F.Cu" "F.Mask" "F.Paste")
			(net "INA230_1_A1")
		)
	)
	(footprint ""
		(layer "F.Cu")
		(at 52.877466 -25.309068 90)
		(property "Reference" "R3234"
			(at 0 0 90)
			(layer "F.SilkS")
			(hide yes)
			(effects
				(font
					(size 1.27 1.27)
				)
			)
		)
		(property "Value" ""
			(at 0 0 90)
			(layer "F.Fab")
			(effects
				(font
					(size 1.27 1.27)
				)
			)
		)
		(duplicate_pad_numbers_are_jumpers no)
		(fp_line
			(start 0.7874 -0.4064)
			(end 0.7874 0.4064)
			(stroke
				(width 0.1524)
				(type default)
			)
			(layer "F.SilkS")
		)
		(fp_line
			(start -0.7874 -0.4064)
			(end 0.7874 -0.4064)
			(stroke
				(width 0.1524)
				(type default)
			)
			(layer "F.SilkS")
		)
		(fp_line
			(start 0.7874 0.4064)
			(end -0.7874 0.4064)
			(stroke
				(width 0.1524)
				(type default)
			)
			(layer "F.SilkS")
		)
		(fp_line
			(start -0.7874 0.4064)
			(end -0.7874 -0.4064)
			(stroke
				(width 0.1524)
				(type default)
			)
			(layer "F.SilkS")
		)
		(fp_line
			(start -0.12065 -0.305054)
			(end -0.12065 -0.2794)
			(stroke
				(width 0.1)
				(type default)
			)
			(layer "F.Fab")
		)
		(fp_line
			(start -0.67945 -0.305054)
			(end -0.12065 -0.305054)
			(stroke
				(width 0.1)
				(type default)
			)
			(layer "F.Fab")
		)
		(fp_line
			(start 0.67945 -0.3048)
			(end 0.67945 0.3048)
			(stroke
				(width 0.1)
				(type default)
			)
			(layer "F.Fab")
		)
		(fp_line
			(start 0.12065 -0.3048)
			(end 0.67945 -0.3048)
			(stroke
				(width 0.1)
				(type default)
			)
			(layer "F.Fab")
		)
		(fp_line
			(start 0.12065 -0.2794)
			(end 0.12065 -0.3048)
			(stroke
				(width 0.1)
				(type default)
			)
			(layer "F.Fab")
		)
		(fp_line
			(start -0.12065 -0.2794)
			(end 0.12065 -0.2794)
			(stroke
				(width 0.1)
				(type default)
			)
			(layer "F.Fab")
		)
		(fp_line
			(start 0.120396 0.2794)
			(end -0.12065 0.2794)
			(stroke
				(width 0.1)
				(type default)
			)
			(layer "F.Fab")
		)
		(fp_line
			(start -0.12065 0.2794)
			(end -0.12065 0.3048)
			(stroke
				(width 0.1)
				(type default)
			)
			(layer "F.Fab")
		)
		(fp_line
			(start 0.67945 0.3048)
			(end 0.120396 0.3048)
			(stroke
				(width 0.1)
				(type default)
			)
			(layer "F.Fab")
		)
		(fp_line
			(start 0.120396 0.3048)
			(end 0.120396 0.2794)
			(stroke
				(width 0.1)
				(type default)
			)
			(layer "F.Fab")
		)
		(fp_line
			(start -0.12065 0.3048)
			(end -0.67945 0.3048)
			(stroke
				(width 0.1)
				(type default)
			)
			(layer "F.Fab")
		)
		(fp_line
			(start -0.67945 0.3048)
			(end -0.67945 -0.305054)
			(stroke
				(width 0.1)
				(type default)
			)
			(layer "F.Fab")
		)
		(pad "1" smd circle
			(at -0.40005 0 90)
			(size 0 0)
			(layers "F.Cu" "F.Mask" "F.Paste")
			(net "OCP_V3_2_AUX_PWR_EN")
		)
		(pad "2" smd circle
			(at 0.40005 0 90)
			(size 0 0)
			(layers "F.Cu" "F.Mask" "F.Paste")
			(net "OCP_V3_2_AUX_PWR_EN_R3")
		)
	)
)
